(kicad_pcb
	(version 20260206)
	(generator "pcbnew")
	(generator_version "10.0")
	(general
		(thickness 1.6)
		(legacy_teardrops no)
	)
	(paper "A4")
	(title_block
		(title "Bryce Canyon_R.DPB_16317-1_OCP.brd")
		(comment 1 "Bryce Canyon / footprints 80-86 of 2099")
	)
	(layers
		(0 "F.Cu" signal "TOP")
		(4 "In1.Cu" signal "L2GND")
		(6 "In2.Cu" signal "L3")
		(8 "In3.Cu" signal "L4VCC")
		(10 "In4.Cu" signal "L5VCC")
		(12 "In5.Cu" signal "L6")
		(14 "In6.Cu" signal "L7GND")
		(2 "B.Cu" signal "BOTTOM")
		(9 "F.Adhes" user "F.Adhesive")
		(11 "B.Adhes" user "B.Adhesive")
		(13 "F.Paste" user "Package Geometry/Pastemask Top")
		(15 "B.Paste" user "Package Geometry/Pastemask Bottom")
		(5 "F.SilkS" user "Ref Des/Silkscreen Top")
		(7 "B.SilkS" user "Ref Des/Silkscreen Bottom")
		(1 "F.Mask" user "Board Geometry/Soldermask Top")
		(3 "B.Mask" user "Board Geometry/Soldermask Bottom")
		(17 "Dwgs.User" user "User.Drawings")
		(19 "Cmts.User" user "User.Comments")
		(21 "Eco1.User" user "User.Eco1")
		(23 "Eco2.User" user "User.Eco2")
		(25 "Edge.Cuts" user "Board Geometry/Outline")
		(27 "Margin" user)
		(31 "F.CrtYd" user "Package Geometry/Place Bound Top")
		(29 "B.CrtYd" user "Package Geometry/Place Bound Bottom")
		(35 "F.Fab" user "Ref Des/Assembly Top")
		(33 "B.Fab" user "Ref Des/Assembly Bottom")
	)
	(footprint ""
		(layer "F.Cu")
		(at 48.537368 -97.328228 -90)
		(property "Reference" "R366"
			(at 0 0 270)
			(layer "F.SilkS")
			(hide yes)
			(effects
				(font
					(size 1.27 1.27)
				)
			)
		)
		(property "Value" "4K7R2F-GP"
			(at 0.064008 -3.993896 270)
			(unlocked yes)
			(layer "F.Fab")
			(hide yes)
			(effects
				(font
					(size 1.016 1.016)
					(thickness 0.1524)
				)
			)
		)
		(property "Device Type" "R402H16"
			(at 0.064008 -5.517896 270)
			(unlocked yes)
			(layer "F.Fab")
			(hide yes)
			(effects
				(font
					(size 1.016 1.016)
					(thickness 0.1524)
				)
			)
		)
		(duplicate_pad_numbers_are_jumpers no)
		(fp_line
			(start -0.508 -0.9398)
			(end -0.508 0.9398)
			(stroke
				(width 0.1524)
				(type default)
			)
			(layer "F.SilkS")
		)
		(fp_line
			(start 0.508 -0.9398)
			(end -0.508 -0.9398)
			(stroke
				(width 0.1524)
				(type default)
			)
			(layer "F.SilkS")
		)
		(fp_rect
			(start -0.508 0.9398)
			(end 0.508 -0.9398)
			(stroke
				(width 0)
				(type default)
			)
			(fill no)
			(layer "F.CrtYd")
		)
		(fp_rect
			(start -0.508 0.9398)
			(end 0.508 -0.9398)
			(stroke
				(width 0)
				(type default)
			)
			(fill no)
			(layer "F.Fab")
		)
		(pad "1" smd custom
			(at 0 -0.4445 270)
			(size 0.1397 0.1397)
			(layers "F.Cu" "F.Mask" "F.Paste")
			(net "DRIVE_B_13_ACT")
			(options
				(clearance outline)
				(anchor circle)
			)
			(primitives
				(gr_poly
					(pts
						(arc
							(start -0.1778 -0.2794)
							(mid -0.249642 -0.249642)
							(end -0.2794 -0.1778)
						)
						(arc
							(start -0.2794 0.1778)
							(mid -0.249642 0.249642)
							(end -0.1778 0.2794)
						)
						(arc
							(start 0.1778 0.2794)
							(mid 0.249642 0.249642)
							(end 0.2794 0.1778)
						)
						(arc
							(start 0.2794 -0.1778)
							(mid 0.249642 -0.249642)
							(end 0.1778 -0.2794)
						)
					)
					(width 0)
					(fill yes)
				)
			)
		)
		(pad "2" smd custom
			(at 0 0.4445 270)
			(size 0.1397 0.1397)
			(layers "F.Cu" "F.Mask" "F.Paste")
			(net "GND")
			(options
				(clearance outline)
				(anchor circle)
			)
			(primitives
				(gr_poly
					(pts
						(arc
							(start -0.1778 -0.2794)
							(mid -0.249642 -0.249642)
							(end -0.2794 -0.1778)
						)
						(arc
							(start -0.2794 0.1778)
							(mid -0.249642 0.249642)
							(end -0.1778 0.2794)
						)
						(arc
							(start 0.1778 0.2794)
							(mid 0.249642 0.249642)
							(end 0.2794 0.1778)
						)
						(arc
							(start 0.2794 -0.1778)
							(mid 0.249642 -0.249642)
							(end 0.1778 -0.2794)
						)
					)
					(width 0)
					(fill yes)
				)
			)
		)
	)
	(footprint ""
		(layer "F.Cu")
		(at 109.855 -133.096 180)
		(property "Reference" "R431"
			(at 0 0 180)
			(layer "F.SilkS")
			(hide yes)
			(effects
				(font
					(size 1.27 1.27)
				)
			)
		)
		(property "Value" "200KR2F-L-GP"
			(at 0.064008 -3.993896 180)
			(unlocked yes)
			(layer "F.Fab")
			(hide yes)
			(effects
				(font
					(size 1.016 1.016)
					(thickness 0.1524)
				)
			)
		)
		(property "Device Type" "R402H16"
			(at 0.064008 -5.517896 180)
			(unlocked yes)
			(layer "F.Fab")
			(hide yes)
			(effects
				(font
					(size 1.016 1.016)
					(thickness 0.1524)
				)
			)
		)
		(duplicate_pad_numbers_are_jumpers no)
		(fp_line
			(start 0.508 -0.9398)
			(end -0.508 -0.9398)
			(stroke
				(width 0.1524)
				(type default)
			)
			(layer "F.SilkS")
		)
		(fp_line
			(start -0.508 -0.9398)
			(end -0.508 0.9398)
			(stroke
				(width 0.1524)
				(type default)
			)
			(layer "F.SilkS")
		)
		(fp_rect
			(start -0.508 0.9398)
			(end 0.508 -0.9398)
			(stroke
				(width 0)
				(type default)
			)
			(fill no)
			(layer "F.CrtYd")
		)
		(fp_rect
			(start -0.508 0.9398)
			(end 0.508 -0.9398)
			(stroke
				(width 0)
				(type default)
			)
			(fill no)
			(layer "F.Fab")
		)
		(pad "1" smd custom
			(at 0 -0.4445 180)
			(size 0.1397 0.1397)
			(layers "F.Cu" "F.Mask" "F.Paste")
			(net "SW_HDD_R15")
			(options
				(clearance outline)
				(anchor circle)
			)
			(primitives
				(gr_poly
					(pts
						(arc
							(start -0.1778 -0.2794)
							(mid -0.249642 -0.249642)
							(end -0.2794 -0.1778)
						)
						(arc
							(start -0.2794 0.1778)
							(mid -0.249642 0.249642)
							(end -0.1778 0.2794)
						)
						(arc
							(start 0.1778 0.2794)
							(mid 0.249642 0.249642)
							(end 0.2794 0.1778)
						)
						(arc
							(start 0.2794 -0.1778)
							(mid 0.249642 -0.249642)
							(end 0.1778 -0.2794)
						)
					)
					(width 0)
					(fill yes)
				)
			)
		)
		(pad "2" smd custom
			(at 0 0.4445 180)
			(size 0.1397 0.1397)
			(layers "F.Cu" "F.Mask" "F.Paste")
			(net "SW_HDD_N15")
			(options
				(clearance outline)
				(anchor circle)
			)
			(primitives
				(gr_poly
					(pts
						(arc
							(start -0.1778 -0.2794)
							(mid -0.249642 -0.249642)
							(end -0.2794 -0.1778)
						)
						(arc
							(start -0.2794 0.1778)
							(mid -0.249642 0.249642)
							(end -0.1778 0.2794)
						)
						(arc
							(start 0.1778 0.2794)
							(mid 0.249642 0.249642)
							(end 0.2794 0.1778)
						)
						(arc
							(start 0.2794 -0.1778)
							(mid 0.249642 -0.249642)
							(end 0.1778 -0.2794)
						)
					)
					(width 0)
					(fill yes)
				)
			)
		)
	)
	(footprint ""
		(layer "F.Cu")
		(at 253.57455 -372.347236 180)
		(property "Reference" "R1039"
			(at 0 0 180)
			(layer "F.SilkS")
			(hide yes)
			(effects
				(font
					(size 1.27 1.27)
				)
			)
		)
		(property "Value" "11KR2F-L-GP"
			(at 0.064008 -3.993896 180)
			(unlocked yes)
			(layer "F.Fab")
			(hide yes)
			(effects
				(font
					(size 1.016 1.016)
					(thickness 0.1524)
				)
			)
		)
		(property "Device Type" "R402H16"
			(at 0.064008 -5.517896 180)
			(unlocked yes)
			(layer "F.Fab")
			(hide yes)
			(effects
				(font
					(size 1.016 1.016)
					(thickness 0.1524)
				)
			)
		)
		(duplicate_pad_numbers_are_jumpers no)
		(fp_line
			(start 0.508 -0.9398)
			(end -0.508 -0.9398)
			(stroke
				(width 0.1524)
				(type default)
			)
			(layer "F.SilkS")
		)
		(fp_line
			(start -0.508 -0.9398)
			(end -0.508 0.9398)
			(stroke
				(width 0.1524)
				(type default)
			)
			(layer "F.SilkS")
		)
		(fp_rect
			(start -0.508 0.9398)
			(end 0.508 -0.9398)
			(stroke
				(width 0)
				(type default)
			)
			(fill no)
			(layer "F.CrtYd")
		)
		(fp_rect
			(start -0.508 0.9398)
			(end 0.508 -0.9398)
			(stroke
				(width 0)
				(type default)
			)
			(fill no)
			(layer "F.Fab")
		)
		(pad "1" smd custom
			(at 0 -0.4445 180)
			(size 0.1397 0.1397)
			(layers "F.Cu" "F.Mask" "F.Paste")
			(net "MB3_P12V_PWGIN_R")
			(options
				(clearance outline)
				(anchor circle)
			)
			(primitives
				(gr_poly
					(pts
						(arc
							(start -0.1778 -0.2794)
							(mid -0.249642 -0.249642)
							(end -0.2794 -0.1778)
						)
						(arc
							(start -0.2794 0.1778)
							(mid -0.249642 0.249642)
							(end -0.1778 0.2794)
						)
						(arc
							(start 0.1778 0.2794)
							(mid 0.249642 0.249642)
							(end 0.2794 0.1778)
						)
						(arc
							(start 0.2794 -0.1778)
							(mid 0.249642 -0.249642)
							(end 0.1778 -0.2794)
						)
					)
					(width 0)
					(fill yes)
				)
			)
		)
		(pad "2" smd custom
			(at 0 0.4445 180)
			(size 0.1397 0.1397)
			(layers "F.Cu" "F.Mask" "F.Paste")
			(net "AGND_CURRENT_DPB")
			(options
				(clearance outline)
				(anchor circle)
			)
			(primitives
				(gr_poly
					(pts
						(arc
							(start -0.1778 -0.2794)
							(mid -0.249642 -0.249642)
							(end -0.2794 -0.1778)
						)
						(arc
							(start -0.2794 0.1778)
							(mid -0.249642 0.249642)
							(end -0.1778 0.2794)
						)
						(arc
							(start 0.1778 0.2794)
							(mid 0.249642 0.249642)
							(end 0.2794 0.1778)
						)
						(arc
							(start 0.2794 -0.1778)
							(mid 0.249642 -0.249642)
							(end 0.1778 -0.2794)
						)
					)
					(width 0)
					(fill yes)
				)
			)
		)
	)
	(footprint ""
		(layer "F.Cu")
		(at 178.181 -134.493 180)
		(property "Reference" "Q77"
			(at 0 0 180)
			(layer "F.SilkS")
			(hide yes)
			(effects
				(font
					(size 1.27 1.27)
				)
			)
		)
		(property "Value" "2N7002KDW-GP"
			(at -2.3622 -8.2042 180)
			(unlocked yes)
			(layer "F.Fab")
			(hide yes)
			(effects
				(font
					(size 1.016 1.016)
					(thickness 0.1524)
				)
			)
		)
		(property "Device Type" "SOT-363H44"
			(at -2.3622 -10.1092 180)
			(unlocked yes)
			(layer "F.Fab")
			(hide yes)
			(effects
				(font
					(size 1.016 1.016)
					(thickness 0.1524)
				)
			)
		)
		(duplicate_pad_numbers_are_jumpers no)
		(fp_line
			(start 1.4478 1.7018)
			(end 1.4478 -1.7018)
			(stroke
				(width 0.1524)
				(type default)
			)
			(layer "F.SilkS")
		)
		(fp_line
			(start 1.4478 -1.7018)
			(end -1.4478 -1.7018)
			(stroke
				(width 0.1524)
				(type default)
			)
			(layer "F.SilkS")
		)
		(fp_line
			(start -1.27 1.524)
			(end -1.27 0.6604)
			(stroke
				(width 0.4826)
				(type default)
			)
			(layer "F.SilkS")
		)
		(fp_line
			(start -1.4478 1.7018)
			(end 1.4478 1.7018)
			(stroke
				(width 0.1524)
				(type default)
			)
			(layer "F.SilkS")
		)
		(fp_line
			(start -1.4478 -1.7018)
			(end -1.4478 1.7018)
			(stroke
				(width 0.1524)
				(type default)
			)
			(layer "F.SilkS")
		)
		(fp_poly
			(pts
				(xy -1.524 -1.778) (xy 1.524 -1.778) (xy 1.524 1.778) (xy -1.524 1.778)
			)
			(stroke
				(width 0)
				(type default)
			)
			(fill no)
			(layer "F.CrtYd")
		)
		(fp_poly
			(pts
				(xy -1.524 -1.778) (xy 1.524 -1.778) (xy 1.524 1.778) (xy -1.524 1.778)
			)
			(stroke
				(width 0)
				(type default)
			)
			(fill no)
			(layer "F.Fab")
		)
		(pad "1" smd rect
			(at -0.65024 0.9398 180)
			(size 0.4064 1.016)
			(layers "F.Cu" "F.Mask" "F.Paste")
			(net "GND")
		)
		(pad "2" smd rect
			(at 0 0.9398 180)
			(size 0.4064 1.016)
			(layers "F.Cu" "F.Mask" "F.Paste")
			(net "SW_PWR_R_HDD17")
		)
		(pad "3" smd rect
			(at 0.65024 0.9398 180)
			(size 0.4064 1.016)
			(layers "F.Cu" "F.Mask" "F.Paste")
			(net "SW_HDD_P17")
		)
		(pad "4" smd rect
			(at 0.65024 -0.9398 180)
			(size 0.4064 1.016)
			(layers "F.Cu" "F.Mask" "F.Paste")
			(net "GND")
		)
		(pad "5" smd rect
			(at 0 -0.9398 180)
			(size 0.4064 1.016)
			(layers "F.Cu" "F.Mask" "F.Paste")
			(net "SW_HDD_G17")
		)
		(pad "6" smd rect
			(at -0.65024 -0.9398 180)
			(size 0.4064 1.016)
			(layers "F.Cu" "F.Mask" "F.Paste")
			(net "SW_HDD_R17")
		)
	)
	(footprint ""
		(layer "F.Cu")
		(at 172.212 -24.384)
		(property "Reference" "Q150"
			(at 0 0 0)
			(layer "F.SilkS")
			(hide yes)
			(effects
				(font
					(size 1.27 1.27)
				)
			)
		)
		(property "Value" "AO4407AL-GP"
			(at -3.707384 -1.5367 0)
			(unlocked yes)
			(layer "F.Fab")
			(hide yes)
			(effects
				(font
					(size 1.016 1.016)
					(thickness 0.1524)
				)
			)
		)
		(property "Device Type" "SOIC8H69"
			(at -3.707384 -3.0607 0)
			(unlocked yes)
			(layer "F.Fab")
			(hide yes)
			(effects
				(font
					(size 1.016 1.016)
					(thickness 0.1524)
				)
			)
		)
		(duplicate_pad_numbers_are_jumpers no)
		(fp_line
			(start -2.7432 -1.4224)
			(end -2.7432 1.4224)
			(stroke
				(width 0.1524)
				(type default)
			)
			(layer "F.SilkS")
		)
		(fp_line
			(start -2.7432 1.4224)
			(end -2.6416 1.4224)
			(stroke
				(width 0.1524)
				(type default)
			)
			(layer "F.SilkS")
		)
		(fp_line
			(start -2.7432 1.4224)
			(end 2.1336 1.4224)
			(stroke
				(width 0.1524)
				(type default)
			)
			(layer "F.SilkS")
		)
		(fp_line
			(start -2.7178 -0.508)
			(end -2.1844 -0.0508)
			(stroke
				(width 0.1524)
				(type default)
			)
			(layer "F.SilkS")
		)
		(fp_line
			(start -2.6289 3.4417)
			(end -2.6289 1.4732)
			(stroke
				(width 0.381)
				(type default)
			)
			(layer "F.SilkS")
		)
		(fp_line
			(start -2.1844 -0.0508)
			(end -2.7178 0.508)
			(stroke
				(width 0.1524)
				(type default)
			)
			(layer "F.SilkS")
		)
		(fp_line
			(start 2.1336 -1.4224)
			(end -2.7432 -1.4224)
			(stroke
				(width 0.1524)
				(type default)
			)
			(layer "F.SilkS")
		)
		(fp_line
			(start 2.1336 1.4224)
			(end 2.1336 -1.4224)
			(stroke
				(width 0.1524)
				(type default)
			)
			(layer "F.SilkS")
		)
		(fp_poly
			(pts
				(xy -2.2098 -1.4224) (xy -2.2098 1.4224) (xy 2.2098 1.4224) (xy 2.2098 -1.4224)
			)
			(stroke
				(width 0)
				(type default)
			)
			(fill yes)
			(layer "F.SilkS")
		)
		(fp_rect
			(start -2.450084 2.999994)
			(end 2.450084 -2.999994)
			(stroke
				(width 0)
				(type default)
			)
			(fill no)
			(layer "F.CrtYd")
		)
		(fp_poly
			(pts
				(xy -2.8194 3.6322) (xy -2.8194 -3.6322) (xy 2.8194 -3.6322) (xy 2.8194 1.18364) (xy 2.450084 1.18364)
				(xy 2.450084 -2.999994) (xy -2.450084 -2.999994) (xy -2.450084 2.999994) (xy 2.450084 2.999994)
				(xy 2.450084 1.18618) (xy 2.8194 1.18618) (xy 2.8194 3.6322)
			)
			(stroke
				(width 0)
				(type default)
			)
			(fill no)
			(layer "F.CrtYd")
		)
		(fp_rect
			(start -2.8194 3.6322)
			(end 2.8194 -3.6322)
			(stroke
				(width 0)
				(type default)
			)
			(fill no)
			(layer "F.Fab")
		)
		(pad "1" smd rect
			(at -1.905 2.54)
			(size 0.635 1.651)
			(layers "F.Cu" "F.Mask" "F.Paste")
			(net "P12V_B")
		)
		(pad "2" smd rect
			(at -0.635 2.54)
			(size 0.635 1.651)
			(layers "F.Cu" "F.Mask" "F.Paste")
			(net "P12V_B")
		)
		(pad "3" smd rect
			(at 0.635 2.54)
			(size 0.635 1.651)
			(layers "F.Cu" "F.Mask" "F.Paste")
			(net "P12V_B")
		)
		(pad "4" smd rect
			(at 1.905 2.54)
			(size 0.635 1.651)
			(layers "F.Cu" "F.Mask" "F.Paste")
			(net "SW_HDD_N29")
		)
		(pad "5" smd rect
			(at 1.905 -2.54)
			(size 0.635 1.651)
			(layers "F.Cu" "F.Mask" "F.Paste")
			(net "P12V_HDD29")
		)
		(pad "6" smd rect
			(at 0.635 -2.54)
			(size 0.635 1.651)
			(layers "F.Cu" "F.Mask" "F.Paste")
			(net "P12V_HDD29")
		)
		(pad "7" smd rect
			(at -0.635 -2.54)
			(size 0.635 1.651)
			(layers "F.Cu" "F.Mask" "F.Paste")
			(net "P12V_HDD29")
		)
		(pad "8" smd rect
			(at -1.905 -2.54)
			(size 0.635 1.651)
			(layers "F.Cu" "F.Mask" "F.Paste")
			(net "P12V_HDD29")
		)
	)
	(footprint ""
		(layer "F.Cu")
		(at 350.766126 -39.705026)
		(property "Reference" "TP176"
			(at 0 0 0)
			(layer "F.SilkS")
			(hide yes)
			(effects
				(font
					(size 1.27 1.27)
				)
			)
		)
		(property "Value" "*"
			(at -0.0508 -1.6764 0)
			(unlocked yes)
			(layer "F.Fab")
			(hide yes)
			(effects
				(font
					(size 1.016 1.016)
					(thickness 0.1524)
				)
			)
		)
		(property "Device Type" "TPAD32"
			(at -0.0508 -3.2004 0)
			(unlocked yes)
			(layer "F.Fab")
			(hide yes)
			(effects
				(font
					(size 1.016 1.016)
					(thickness 0.1524)
				)
			)
		)
		(duplicate_pad_numbers_are_jumpers no)
		(fp_poly
			(pts
				(arc
					(start 0.4064 0)
					(mid -0.4064 0)
					(end 0.4064 0)
				)
			)
			(stroke
				(width 0)
				(type default)
			)
			(fill no)
			(layer "F.CrtYd")
		)
		(fp_poly
			(pts
				(arc
					(start 0.7112 0)
					(mid -0.7112 0)
					(end 0.7112 0)
				)
			)
			(stroke
				(width 0)
				(type default)
			)
			(fill no)
			(layer "F.Fab")
		)
		(pad "1" smd circle
			(at 0 0)
			(size 0.8128 0.8128)
			(layers "F.Cu" "F.Mask" "F.Paste")
			(net "ACT_HDD_31")
		)
	)
	(footprint ""
		(layer "F.Cu")
		(at 173.482 -363.22 90)
		(property "Reference" "R1005"
			(at 0 0 90)
			(layer "F.SilkS")
			(hide yes)
			(effects
				(font
					(size 1.27 1.27)
				)
			)
		)
		(property "Value" "100KR2F-L1-GP"
			(at 0.064008 -3.993896 90)
			(unlocked yes)
			(layer "F.Fab")
			(hide yes)
			(effects
				(font
					(size 1.016 1.016)
					(thickness 0.1524)
				)
			)
		)
		(property "Device Type" "R402H16"
			(at 0.064008 -5.517896 90)
			(unlocked yes)
			(layer "F.Fab")
			(hide yes)
			(effects
				(font
					(size 1.016 1.016)
					(thickness 0.1524)
				)
			)
		)
		(duplicate_pad_numbers_are_jumpers no)
		(fp_line
			(start 0.508 -0.9398)
			(end -0.508 -0.9398)
			(stroke
				(width 0.1524)
				(type default)
			)
			(layer "F.SilkS")
		)
		(fp_line
			(start -0.508 -0.9398)
			(end -0.508 0.9398)
			(stroke
				(width 0.1524)
				(type default)
			)
			(layer "F.SilkS")
		)
		(fp_rect
			(start -0.508 0.9398)
			(end 0.508 -0.9398)
			(stroke
				(width 0)
				(type default)
			)
			(fill no)
			(layer "F.CrtYd")
		)
		(fp_rect
			(start -0.508 0.9398)
			(end 0.508 -0.9398)
			(stroke
				(width 0)
				(type default)
			)
			(fill no)
			(layer "F.Fab")
		)
		(pad "1" smd custom
			(at 0 -0.4445 90)
			(size 0.1397 0.1397)
			(layers "F.Cu" "F.Mask" "F.Paste")
			(net "MB0_VCAP_R")
			(options
				(clearance outline)
				(anchor circle)
			)
			(primitives
				(gr_poly
					(pts
						(arc
							(start -0.1778 -0.2794)
							(mid -0.249642 -0.249642)
							(end -0.2794 -0.1778)
						)
						(arc
							(start -0.2794 0.1778)
							(mid -0.249642 0.249642)
							(end -0.1778 0.2794)
						)
						(arc
							(start 0.1778 0.2794)
							(mid 0.249642 0.249642)
							(end 0.2794 0.1778)
						)
						(arc
							(start 0.2794 -0.1778)
							(mid 0.249642 -0.249642)
							(end 0.1778 -0.2794)
						)
					)
					(width 0)
					(fill yes)
				)
			)
		)
		(pad "2" smd custom
			(at 0 0.4445 90)
			(size 0.1397 0.1397)
			(layers "F.Cu" "F.Mask" "F.Paste")
			(net "MB0_ISET_R")
			(options
				(clearance outline)
				(anchor circle)
			)
			(primitives
				(gr_poly
					(pts
						(arc
							(start -0.1778 -0.2794)
							(mid -0.249642 -0.249642)
							(end -0.2794 -0.1778)
						)
						(arc
							(start -0.2794 0.1778)
							(mid -0.249642 0.249642)
							(end -0.1778 0.2794)
						)
						(arc
							(start 0.1778 0.2794)
							(mid 0.249642 0.249642)
							(end 0.2794 0.1778)
						)
						(arc
							(start 0.2794 -0.1778)
							(mid 0.249642 -0.249642)
							(end 0.1778 -0.2794)
						)
					)
					(width 0)
					(fill yes)
				)
			)
		)
	)
)
